(kicad_pcb
	(version 20260206)
	(generator "pcbnew")
	(generator_version "10.0")
	(general
		(thickness 1.6)
		(legacy_teardrops no)
	)
	(paper "A4")
	(title_block
		(title "04192023_DAF0TMB3IC0_F0TG_MB_C_brd_V02_OCP.brd")
		(comment 1 "Grand Teton / footprints 2578-2579 of 8354")
	)
	(layers
		(0 "F.Cu" signal "TOP")
		(4 "In1.Cu" signal "GND")
		(6 "In2.Cu" signal "IN1")
		(8 "In3.Cu" signal "GND1")
		(10 "In4.Cu" signal "IN2")
		(12 "In5.Cu" signal "GND2")
		(14 "In6.Cu" signal "IN3")
		(16 "In7.Cu" signal "GND3")
		(18 "In8.Cu" signal "VCC")
		(20 "In9.Cu" signal "VCC1")
		(22 "In10.Cu" signal "GND4")
		(24 "In11.Cu" signal "IN4")
		(26 "In12.Cu" signal "GND5")
		(28 "In13.Cu" signal "IN5")
		(30 "In14.Cu" signal "GND6")
		(32 "In15.Cu" signal "IN6")
		(34 "In16.Cu" signal "GND7")
		(2 "B.Cu" signal "BOTTOM")
		(9 "F.Adhes" user "F.Adhesive")
		(11 "B.Adhes" user "B.Adhesive")
		(13 "F.Paste" user "Package Geometry/Pastemask Top")
		(15 "B.Paste" user "Package Geometry/Pastemask Bottom")
		(5 "F.SilkS" user "Ref Des/Silkscreen Top")
		(7 "B.SilkS" user "Ref Des/Silkscreen Bottom")
		(1 "F.Mask" user "Board Geometry/Soldermask Top")
		(3 "B.Mask" user "Board Geometry/Soldermask Bottom")
		(17 "Dwgs.User" user "User.Drawings")
		(19 "Cmts.User" user "User.Comments")
		(21 "Eco1.User" user "User.Eco1")
		(23 "Eco2.User" user "User.Eco2")
		(25 "Edge.Cuts" user "Board Geometry/Outline")
		(27 "Margin" user)
		(31 "F.CrtYd" user "Package Geometry/Place Bound Top")
		(29 "B.CrtYd" user "Package Geometry/Place Bound Bottom")
		(35 "F.Fab" user "Ref Des/Assembly Top")
		(33 "B.Fab" user "Ref Des/Assembly Bottom")
	)
	(footprint ""
		(layer "F.Cu")
		(at 381.077978 -182.786528 180)
		(property "Reference" "PU46"
			(at 1.867916 -7.072122 0)
			(unlocked yes)
			(layer "F.SilkS")
			(effects
				(font
					(size 0.7874 0.5842)
					(thickness 0.1524)
				)
				(justify left)
			)
		)
		(property "Value" ""
			(at 0 0 180)
			(layer "F.Fab")
			(effects
				(font
					(size 1.27 1.27)
				)
			)
		)
		(duplicate_pad_numbers_are_jumpers no)
		(fp_line
			(start 2.500122 2.999994)
			(end 2.2987 2.999994)
			(stroke
				(width 0.1524)
				(type default)
			)
			(layer "F.SilkS")
		)
		(fp_line
			(start 2.500122 2.339594)
			(end 2.500122 2.999994)
			(stroke
				(width 0.1524)
				(type default)
			)
			(layer "F.SilkS")
		)
		(fp_line
			(start 2.500122 -2.999994)
			(end 2.500122 -2.44348)
			(stroke
				(width 0.1524)
				(type default)
			)
			(layer "F.SilkS")
		)
		(fp_line
			(start 2.31394 -2.999994)
			(end 2.500122 -2.999994)
			(stroke
				(width 0.1524)
				(type default)
			)
			(layer "F.SilkS")
		)
		(fp_line
			(start -2.2987 2.999994)
			(end -2.500122 2.999994)
			(stroke
				(width 0.1524)
				(type default)
			)
			(layer "F.SilkS")
		)
		(fp_line
			(start -2.500122 2.999994)
			(end -2.500122 2.339594)
			(stroke
				(width 0.1524)
				(type default)
			)
			(layer "F.SilkS")
		)
		(fp_line
			(start -2.500122 0.6604)
			(end -2.500122 0.229108)
			(stroke
				(width 0.1524)
				(type default)
			)
			(layer "F.SilkS")
		)
		(fp_line
			(start -2.500122 -2.529078)
			(end -2.500122 -2.999994)
			(stroke
				(width 0.1524)
				(type default)
			)
			(layer "F.SilkS")
		)
		(fp_line
			(start -2.500122 -2.999994)
			(end -2.24409 -2.999994)
			(stroke
				(width 0.1524)
				(type default)
			)
			(layer "F.SilkS")
		)
		(fp_poly
			(pts
				(xy -2.788666 -2.483612) (xy -3.45948 -2.707386) (xy -3.01244 -3.154426)
			)
			(stroke
				(width 0)
				(type default)
			)
			(fill yes)
			(layer "F.SilkS")
		)
		(fp_line
			(start 2.500122 2.999994)
			(end -2.500122 2.999994)
			(stroke
				(width 0.1)
				(type default)
			)
			(layer "F.Fab")
		)
		(fp_line
			(start 2.500122 -2.999994)
			(end 2.500122 2.999994)
			(stroke
				(width 0.1)
				(type default)
			)
			(layer "F.Fab")
		)
		(fp_line
			(start -2.500122 2.999994)
			(end -2.500122 -2.999994)
			(stroke
				(width 0.1)
				(type default)
			)
			(layer "F.Fab")
		)
		(fp_line
			(start -2.500122 -2.999994)
			(end 2.500122 -2.999994)
			(stroke
				(width 0.1)
				(type default)
			)
			(layer "F.Fab")
		)
		(fp_poly
			(pts
				(xy -4.218432 -2.783078) (xy -4.218432 -1.767078) (xy -3.202432 -2.275078)
			)
			(stroke
				(width 0)
				(type default)
			)
			(fill yes)
			(layer "F.Fab")
		)
		(pad "1" smd rect
			(at -2.400046 -2.275078 270)
			(size 0.2286 0.6096)
			(layers "F.Cu" "F.Mask" "F.Paste")
			(net "PVDDCR_CPU0_P0_VOS3")
		)
		(pad "2" smd rect
			(at -2.400046 -1.82499 270)
			(size 0.2286 0.6096)
			(layers "F.Cu" "F.Mask" "F.Paste")
			(net "GND")
		)
		(pad "3" smd rect
			(at -2.400046 -1.374902 270)
			(size 0.2286 0.6096)
			(layers "F.Cu" "F.Mask" "F.Paste")
			(net "PVDDCR_CPU0_P0_VCC3")
		)
		(pad "4" smd rect
			(at -2.400046 -0.925068 270)
			(size 0.2286 0.6096)
			(layers "F.Cu" "F.Mask" "F.Paste")
			(net "PVDDCR_CPU0_P0_PVCC")
		)
		(pad "5" smd rect
			(at -2.400046 -0.47498 270)
			(size 0.2286 0.6096)
			(layers "F.Cu" "F.Mask" "F.Paste")
			(net "GND")
		)
		(pad "6" smd rect
			(at -2.400046 -0.024892 270)
			(size 0.2286 0.6096)
			(layers "F.Cu" "F.Mask" "F.Paste")
			(net "NC_PVDDCR_CPU0_P0_GL1_3")
		)
		(pad "7_9-20_24" smd circle
			(at 0 1.150112 270)
			(size 0 0)
			(layers "F.Cu" "F.Mask" "F.Paste")
			(net "GND")
		)
		(pad "10_19" smd rect
			(at 0 2.899918 270)
			(size 0.6096 4.318)
			(layers "F.Cu" "F.Mask" "F.Paste")
			(net "SW_PVDDCR_CPU0_P0_SW3")
		)
		(pad "25_29" smd rect
			(at 1.549908 -1.279906 90)
			(size 2.0574 2.3114)
			(layers "F.Cu" "F.Mask" "F.Paste")
			(net "SW_P12V_AUX_PVDDCR_CPU0_P0_FLT")
		)
		(pad "30" smd rect
			(at 2.05994 -2.899918 180)
			(size 0.2286 0.6096)
			(layers "F.Cu" "F.Mask" "F.Paste")
			(net "SW_P12V_AUX_PVDDCR_CPU0_P0_FLT")
		)
		(pad "31" smd rect
			(at 1.610106 -2.899918 180)
			(size 0.2286 0.6096)
			(layers "F.Cu" "F.Mask" "F.Paste")
			(net "NC_PVDDCR_CPU0_P0_DNC3")
		)
		(pad "32" smd rect
			(at 1.160018 -2.899918 180)
			(size 0.2286 0.6096)
			(layers "F.Cu" "F.Mask" "F.Paste")
			(net "SW_PVDDCR_CPU0_P0_PH3")
		)
		(pad "33" smd rect
			(at 0.70993 -2.899918 180)
			(size 0.2286 0.6096)
			(layers "F.Cu" "F.Mask" "F.Paste")
			(net "SW_PVDDCR_CPU0_P0_BOOT3")
		)
		(pad "34" smd rect
			(at 0.260096 -2.899918 180)
			(size 0.2286 0.6096)
			(layers "F.Cu" "F.Mask" "F.Paste")
			(net "PVDDCR_CPU0_P0_PWM3")
		)
		(pad "35" smd rect
			(at -0.189992 -2.899918 180)
			(size 0.2286 0.6096)
			(layers "F.Cu" "F.Mask" "F.Paste")
			(net "PVDDCR_CPU0_P0_VCC3")
		)
		(pad "36" smd rect
			(at -0.64008 -2.899918 180)
			(size 0.2286 0.6096)
			(layers "F.Cu" "F.Mask" "F.Paste")
			(net "PVDDCR_CPU0_P0_TEMP0")
		)
		(pad "37" smd rect
			(at -1.089914 -2.899918 180)
			(size 0.2286 0.6096)
			(layers "F.Cu" "F.Mask" "F.Paste")
			(net "PVDDCR_CPU0_P0_LSET3")
		)
		(pad "38" smd rect
			(at -1.540002 -2.899918 180)
			(size 0.2286 0.6096)
			(layers "F.Cu" "F.Mask" "F.Paste")
			(net "PVDDCR_CPU0_P0_IMON3")
		)
		(pad "39" smd rect
			(at -1.99009 -2.899918 180)
			(size 0.2286 0.6096)
			(layers "F.Cu" "F.Mask" "F.Paste")
			(net "PVDDCR_CPU0_P0_VCCS")
		)
		(pad "40" smd rect
			(at -0.87503 -1.27508 180)
			(size 1.7526 1.9558)
			(layers "F.Cu" "F.Mask" "F.Paste")
			(net "GND")
		)
		(pad "41" smd rect
			(at -1.525016 0.249936 90)
			(size 0.3048 0.4572)
			(layers "F.Cu" "F.Mask" "F.Paste")
			(net "NC_PVDDCR_CPU0_P0_GL2_3")
		)
		(zone
			(layer "F.Cu")
			(hatch none 0.5)
			(connect_pads
				(clearance 0)
			)
			(min_thickness 0.25)
			(keepout
				(tracks not_allowed)
				(vias allowed)
				(pads allowed)
				(copperpour not_allowed)
				(footprints allowed)
			)
			(placement
				(enabled no)
				(sheetname "")
			)
			(fill
				(thermal_gap 0.5)
				(thermal_bridge_width 0.5)
				(island_removal_mode 0)
			)
			(polygon
				(pts
					(xy 383.5781 -185.334402) (xy 383.5781 -185.037222) (xy 378.577856 -185.037222) (xy 378.577856 -185.33491)
					(xy 378.868178 -185.33491) (xy 378.868178 -185.330846) (xy 383.287778 -185.330846) (xy 383.287778 -185.334402)
				)
			)
		)
		(zone
			(layer "F.Cu")
			(hatch none 0.5)
			(connect_pads
				(clearance 0)
			)
			(min_thickness 0.25)
			(keepout
				(tracks not_allowed)
				(vias allowed)
				(pads allowed)
				(copperpour not_allowed)
				(footprints allowed)
			)
			(placement
				(enabled no)
				(sheetname "")
			)
			(fill
				(thermal_gap 0.5)
				(thermal_bridge_width 0.5)
				(island_removal_mode 0)
			)
			(polygon
				(pts
					(xy 381.025908 -182.53456) (xy 381.025908 -180.482748) (xy 382.880108 -180.482748) (xy 382.880108 -180.723794)
					(xy 383.122424 -180.723794) (xy 383.122424 -180.24221) (xy 379.244098 -180.24221) (xy 379.244098 -180.427122)
					(xy 380.73457 -180.427122) (xy 380.73457 -182.586122) (xy 378.577856 -182.586122) (xy 378.577856 -182.835804)
					(xy 380.724664 -182.835804)
				)
			)
		)
	)
	(footprint ""
		(layer "F.Cu")
		(at 253.86157 -51.382422 180)
		(property "Reference" "PU292"
			(at -1.008634 -4.773422 0)
			(unlocked yes)
			(layer "F.SilkS")
			(effects
				(font
					(size 0.7874 0.5842)
					(thickness 0.1524)
				)
				(justify left)
			)
		)
		(property "Value" ""
			(at 0 0 180)
			(layer "F.Fab")
			(effects
				(font
					(size 1.27 1.27)
				)
			)
		)
		(duplicate_pad_numbers_are_jumpers no)
		(fp_line
			(start 1.549908 2.549906)
			(end 1.549908 2.253996)
			(stroke
				(width 0.1524)
				(type default)
			)
			(layer "F.SilkS")
		)
		(fp_line
			(start 1.549908 -2.253996)
			(end 1.549908 -2.549906)
			(stroke
				(width 0.1524)
				(type default)
			)
			(layer "F.SilkS")
		)
		(fp_line
			(start 1.549908 -2.549906)
			(end 0.752094 -2.549906)
			(stroke
				(width 0.1524)
				(type default)
			)
			(layer "F.SilkS")
		)
		(fp_line
			(start 0.753872 2.549906)
			(end 1.549908 2.549906)
			(stroke
				(width 0.1524)
				(type default)
			)
			(layer "F.SilkS")
		)
		(fp_line
			(start 0.2413 -2.549906)
			(end -0.2413 -2.549906)
			(stroke
				(width 0.1524)
				(type default)
			)
			(layer "F.SilkS")
		)
		(fp_line
			(start -0.245872 2.549906)
			(end 0.245872 2.549906)
			(stroke
				(width 0.1524)
				(type default)
			)
			(layer "F.SilkS")
		)
		(fp_line
			(start -0.752094 -2.549906)
			(end -1.549908 -2.549906)
			(stroke
				(width 0.1524)
				(type default)
			)
			(layer "F.SilkS")
		)
		(fp_line
			(start -1.549908 2.549906)
			(end -0.753872 2.549906)
			(stroke
				(width 0.1524)
				(type default)
			)
			(layer "F.SilkS")
		)
		(fp_line
			(start -1.549908 2.253996)
			(end -1.549908 2.549906)
			(stroke
				(width 0.1524)
				(type default)
			)
			(layer "F.SilkS")
		)
		(fp_line
			(start -1.549908 -2.549906)
			(end -1.549908 -2.251964)
			(stroke
				(width 0.1524)
				(type default)
			)
			(layer "F.SilkS")
		)
		(fp_poly
			(pts
				(xy -2.18694 -3.538982) (xy -2.02057 -2.601722) (xy -2.8702 -3.031236)
			)
			(stroke
				(width 0)
				(type default)
			)
			(fill yes)
			(layer "F.SilkS")
		)
		(fp_line
			(start 1.549908 2.549906)
			(end 1.549908 -2.549906)
			(stroke
				(width 0.1)
				(type default)
			)
			(layer "F.Fab")
		)
		(fp_line
			(start 1.549908 -2.549906)
			(end -1.549908 -2.549906)
			(stroke
				(width 0.1)
				(type default)
			)
			(layer "F.Fab")
		)
		(fp_line
			(start -1.549908 2.549906)
			(end 1.549908 2.549906)
			(stroke
				(width 0.1)
				(type default)
			)
			(layer "F.Fab")
		)
		(fp_line
			(start -1.549908 -2.549906)
			(end -1.549908 2.549906)
			(stroke
				(width 0.1)
				(type default)
			)
			(layer "F.Fab")
		)
		(fp_poly
			(pts
				(xy -1.891538 -1.999996) (xy -2.7432 -1.574292) (xy -2.7432 -2.4257)
			)
			(stroke
				(width 0)
				(type default)
			)
			(fill yes)
			(layer "F.Fab")
		)
		(fp_text user "12"
			(at 3.551428 5.08762 90)
			(unlocked yes)
			(layer "F.SilkS")
			(effects
				(font
					(size 0.635 0.4064)
					(thickness 0.1524)
				)
			)
		)
		(fp_text user "11"
			(at 2.3241 5.249672 180)
			(unlocked yes)
			(layer "F.SilkS")
			(effects
				(font
					(size 0.635 0.4064)
					(thickness 0.1524)
				)
			)
		)
		(fp_text user "20"
			(at 2.141728 -3.6449 90)
			(unlocked yes)
			(layer "F.SilkS")
			(effects
				(font
					(size 0.635 0.4064)
					(thickness 0.1524)
				)
			)
		)
		(fp_text user "21_22"
			(at -0.0762 -3.401568 180)
			(unlocked yes)
			(layer "F.SilkS")
			(effects
				(font
					(size 0.635 0.4064)
					(thickness 0.1524)
				)
			)
		)
		(fp_text user "10"
			(at -1.46558 5.945632 180)
			(unlocked yes)
			(layer "F.SilkS")
			(effects
				(font
					(size 0.635 0.4064)
					(thickness 0.1524)
				)
			)
		)
		(fp_text user "9"
			(at -2.51587 2.156206 90)
			(unlocked yes)
			(layer "F.SilkS")
			(effects
				(font
					(size 0.635 0.4064)
					(thickness 0.1524)
				)
			)
		)
		(fp_text user "12"
			(at 2.207768 2.7178 90)
			(unlocked yes)
			(layer "F.Fab")
			(effects
				(font
					(size 0.635 0.4064)
					(thickness 0.1524)
				)
			)
		)
		(fp_text user "20"
			(at 2.055368 -2.7686 90)
			(unlocked yes)
			(layer "F.Fab")
			(effects
				(font
					(size 0.635 0.4064)
					(thickness 0.1524)
				)
			)
		)
		(fp_text user "11"
			(at 1.1938 3.329432 180)
			(unlocked yes)
			(layer "F.Fab")
			(effects
				(font
					(size 0.635 0.4064)
					(thickness 0.1524)
				)
			)
		)
		(fp_text user "21_22"
			(at -0.0762 -3.401568 180)
			(unlocked yes)
			(layer "F.Fab")
			(effects
				(font
					(size 0.635 0.4064)
					(thickness 0.1524)
				)
			)
		)
		(fp_text user "10"
			(at -1.4224 3.253232 180)
			(unlocked yes)
			(layer "F.Fab")
			(effects
				(font
					(size 0.635 0.4064)
					(thickness 0.1524)
				)
			)
		)
		(fp_text user "9"
			(at -2.338832 2.5908 90)
			(unlocked yes)
			(layer "F.Fab")
			(effects
				(font
					(size 0.635 0.4064)
					(thickness 0.1524)
				)
			)
		)
		(pad "1" smd circle
			(at -1.374902 -1.999996 90)
			(size 0 0)
			(layers "F.Cu" "F.Mask" "F.Paste")
			(net "P12V_E1S_EN_0_R2")
		)
		(pad "2" smd rect
			(at -1.400048 -1.500124 90)
			(size 0.254 0.8128)
			(layers "F.Cu" "F.Mask" "F.Paste")
			(net "GND")
		)
		(pad "3" smd rect
			(at -1.400048 -0.999998 90)
			(size 0.254 0.8128)
			(layers "F.Cu" "F.Mask" "F.Paste")
			(net "GND")
		)
		(pad "4" smd rect
			(at -1.400048 -0.499872 90)
			(size 0.254 0.8128)
			(layers "F.Cu" "F.Mask" "F.Paste")
			(net "P12V_E1S_TIMER_0")
		)
		(pad "5" smd rect
			(at -1.400048 0 90)
			(size 0.254 0.8128)
			(layers "F.Cu" "F.Mask" "F.Paste")
			(net "P12V_E1S_ISET_0")
		)
		(pad "6" smd rect
			(at -1.400048 0.499872 90)
			(size 0.254 0.8128)
			(layers "F.Cu" "F.Mask" "F.Paste")
			(net "P12V_E1S_SS_0")
		)
		(pad "7" smd rect
			(at -1.400048 0.999998 90)
			(size 0.254 0.8128)
			(layers "F.Cu" "F.Mask" "F.Paste")
			(net "GND")
		)
		(pad "8" smd rect
			(at -1.400048 1.500124 90)
			(size 0.254 0.8128)
			(layers "F.Cu" "F.Mask" "F.Paste")
			(net "P12V_E1S_IMON_0")
		)
		(pad "9" smd rect
			(at -1.400048 1.999996 90)
			(size 0.254 0.8128)
			(layers "F.Cu" "F.Mask" "F.Paste")
			(net "P12V_E1S_FLTB_0")
		)
		(pad "10" smd rect
			(at -0.499872 2.400046 180)
			(size 0.254 0.8128)
			(layers "F.Cu" "F.Mask" "F.Paste")
			(net "HP_LVC3_E1S_0_HSC_PWRGD")
		)
		(pad "11" smd rect
			(at 0.499872 2.400046 180)
			(size 0.254 0.8128)
			(layers "F.Cu" "F.Mask" "F.Paste")
			(net "P12V_E1S_OV_FB_0")
		)
		(pad "12" smd rect
			(at 1.400048 1.999996 90)
			(size 0.254 0.8128)
			(layers "F.Cu" "F.Mask" "F.Paste")
			(net "P12V_E1S_AVIN_PD_0")
		)
		(pad "13" smd rect
			(at 1.400048 1.500124 90)
			(size 0.254 0.8128)
			(layers "F.Cu" "F.Mask" "F.Paste")
			(net "P12V_E1S_0")
		)
		(pad "14" smd rect
			(at 1.400048 0.999998 90)
			(size 0.254 0.8128)
			(layers "F.Cu" "F.Mask" "F.Paste")
			(net "P12V_E1S_0")
		)
		(pad "15" smd rect
			(at 1.400048 0.499872 90)
			(size 0.254 0.8128)
			(layers "F.Cu" "F.Mask" "F.Paste")
			(net "P12V_E1S_0")
		)
		(pad "16" smd rect
			(at 1.400048 0 90)
			(size 0.254 0.8128)
			(layers "F.Cu" "F.Mask" "F.Paste")
			(net "P12V_E1S_0")
		)
		(pad "17" smd rect
			(at 1.400048 -0.499872 90)
			(size 0.254 0.8128)
			(layers "F.Cu" "F.Mask" "F.Paste")
			(net "P12V_E1S_0")
		)
		(pad "18" smd rect
			(at 1.400048 -0.999998 90)
			(size 0.254 0.8128)
			(layers "F.Cu" "F.Mask" "F.Paste")
			(net "P12V_E1S_0")
		)
		(pad "19" smd rect
			(at 1.400048 -1.500124 90)
			(size 0.254 0.8128)
			(layers "F.Cu" "F.Mask" "F.Paste")
			(net "P12V_E1S_0")
		)
		(pad "20" smd rect
			(at 1.400048 -1.999996 90)
			(size 0.254 0.8128)
			(layers "F.Cu" "F.Mask" "F.Paste")
			(net "P12V_E1S_0")
		)
		(pad "21_22" smd circle
			(at 0.499872 -2.337562 90)
			(size 0 0)
			(layers "F.Cu" "F.Mask" "F.Paste")
			(net "P12V_AUX")
		)
		(pad "23" smd rect
			(at 0 -1.100074 90)
			(size 0.254 1.27)
			(layers "F.Cu" "F.Mask" "F.Paste")
			(net "P12V_AUX")
		)
		(pad "24" smd rect
			(at 0 -0.199898 90)
			(size 0.254 1.27)
			(layers "F.Cu" "F.Mask" "F.Paste")
			(net "P12V_AUX")
		)
		(pad "25" smd rect
			(at 0 0.700024 90)
			(size 0.254 1.27)
			(layers "F.Cu" "F.Mask" "F.Paste")
			(net "P12V_AUX")
		)
		(pad "26" smd rect
			(at 0 1.599946 90)
			(size 0.254 1.27)
			(layers "F.Cu" "F.Mask" "F.Paste")
			(net "P12V_AUX")
		)
	)
)
